(kicad_pcb
	(version 20260206)
	(generator "pcbnew")
	(generator_version "10.0")
	(general
		(thickness 1.6)
		(legacy_teardrops no)
	)
	(paper "A4")
	(title_block
		(title "01162023_DA0F0TEBIF0_F0T_Expander_BD_F_brd_V02_OCP.brd")
		(comment 1 "Grand Teton / footprints 6260-6268 of 9728")
	)
	(layers
		(0 "F.Cu" signal "TOP")
		(4 "In1.Cu" signal "GND")
		(6 "In2.Cu" signal "VCC")
		(8 "In3.Cu" signal "VCC1")
		(10 "In4.Cu" signal "GND1")
		(12 "In5.Cu" signal "IN1")
		(14 "In6.Cu" signal "GND2")
		(16 "In7.Cu" signal "IN2")
		(18 "In8.Cu" signal "GND3")
		(20 "In9.Cu" signal "IN3")
		(22 "In10.Cu" signal "GND4")
		(24 "In11.Cu" signal "IN4")
		(26 "In12.Cu" signal "GND5")
		(28 "In13.Cu" signal "IN5")
		(30 "In14.Cu" signal "GND6")
		(32 "In15.Cu" signal "IN6")
		(34 "In16.Cu" signal "GND7")
		(2 "B.Cu" signal "BOTTOM")
		(9 "F.Adhes" user "F.Adhesive")
		(11 "B.Adhes" user "B.Adhesive")
		(13 "F.Paste" user "Package Geometry/Pastemask Top")
		(15 "B.Paste" user "Package Geometry/Pastemask Bottom")
		(5 "F.SilkS" user "Ref Des/Silkscreen Top")
		(7 "B.SilkS" user "Ref Des/Silkscreen Bottom")
		(1 "F.Mask" user "Board Geometry/Soldermask Top")
		(3 "B.Mask" user "Board Geometry/Soldermask Bottom")
		(17 "Dwgs.User" user "User.Drawings")
		(19 "Cmts.User" user "User.Comments")
		(21 "Eco1.User" user "User.Eco1")
		(23 "Eco2.User" user "User.Eco2")
		(25 "Edge.Cuts" user "Board Geometry/Outline")
		(27 "Margin" user)
		(31 "F.CrtYd" user "Package Geometry/Place Bound Top")
		(29 "B.CrtYd" user "Package Geometry/Place Bound Bottom")
		(35 "F.Fab" user "Ref Des/Assembly Top")
		(33 "B.Fab" user "Ref Des/Assembly Bottom")
	)
	(footprint ""
		(layer "F.Cu")
		(at 381.587756 -291.619432)
		(property "Reference" "C3564"
			(at 0 0 0)
			(layer "F.SilkS")
			(hide yes)
			(effects
				(font
					(size 1.27 1.27)
				)
			)
		)
		(property "Value" ""
			(at 0 0 0)
			(layer "F.Fab")
			(effects
				(font
					(size 1.27 1.27)
				)
			)
		)
		(duplicate_pad_numbers_are_jumpers no)
		(fp_line
			(start -1.2954 -0.5842)
			(end 1.2954 -0.5842)
			(stroke
				(width 0.1524)
				(type default)
			)
			(layer "F.SilkS")
		)
		(fp_line
			(start -1.2954 0.5842)
			(end -1.2954 -0.5842)
			(stroke
				(width 0.1524)
				(type default)
			)
			(layer "F.SilkS")
		)
		(fp_line
			(start 1.2954 -0.5842)
			(end 1.2954 0.5842)
			(stroke
				(width 0.1524)
				(type default)
			)
			(layer "F.SilkS")
		)
		(fp_line
			(start 1.2954 0.5842)
			(end -1.2954 0.5842)
			(stroke
				(width 0.1524)
				(type default)
			)
			(layer "F.SilkS")
		)
		(fp_line
			(start -1.1938 -0.4064)
			(end -0.8636 -0.4064)
			(stroke
				(width 0.1)
				(type default)
			)
			(layer "F.Fab")
		)
		(fp_line
			(start -1.1938 0.4064)
			(end -1.1938 -0.4064)
			(stroke
				(width 0.1)
				(type default)
			)
			(layer "F.Fab")
		)
		(fp_line
			(start -0.8636 -0.4572)
			(end 0.8636 -0.4572)
			(stroke
				(width 0.1)
				(type default)
			)
			(layer "F.Fab")
		)
		(fp_line
			(start -0.8636 -0.4064)
			(end -0.8636 -0.4572)
			(stroke
				(width 0.1)
				(type default)
			)
			(layer "F.Fab")
		)
		(fp_line
			(start -0.8636 0.4064)
			(end -1.1938 0.4064)
			(stroke
				(width 0.1)
				(type default)
			)
			(layer "F.Fab")
		)
		(fp_line
			(start -0.8636 0.4572)
			(end -0.8636 0.4064)
			(stroke
				(width 0.1)
				(type default)
			)
			(layer "F.Fab")
		)
		(fp_line
			(start 0.8636 -0.4572)
			(end 0.8636 -0.4064)
			(stroke
				(width 0.1)
				(type default)
			)
			(layer "F.Fab")
		)
		(fp_line
			(start 0.8636 -0.4064)
			(end 1.1938 -0.4064)
			(stroke
				(width 0.1)
				(type default)
			)
			(layer "F.Fab")
		)
		(fp_line
			(start 0.8636 0.4064)
			(end 0.8636 0.4572)
			(stroke
				(width 0.1)
				(type default)
			)
			(layer "F.Fab")
		)
		(fp_line
			(start 0.8636 0.4572)
			(end -0.8636 0.4572)
			(stroke
				(width 0.1)
				(type default)
			)
			(layer "F.Fab")
		)
		(fp_line
			(start 1.1938 -0.4064)
			(end 1.1938 0.4064)
			(stroke
				(width 0.1)
				(type default)
			)
			(layer "F.Fab")
		)
		(fp_line
			(start 1.1938 0.4064)
			(end 0.8636 0.4064)
			(stroke
				(width 0.1)
				(type default)
			)
			(layer "F.Fab")
		)
		(pad "1" smd rect
			(at -0.7366 0 270)
			(size 0.7112 0.8128)
			(layers "F.Cu" "F.Mask" "F.Paste")
			(net "PCEPLL4_VDDA18_PEX3")
		)
		(pad "2" smd rect
			(at 0.7366 0 270)
			(size 0.7112 0.8128)
			(layers "F.Cu" "F.Mask" "F.Paste")
			(net "GND")
		)
	)
	(footprint ""
		(layer "F.Cu")
		(at 340.729316 -308.524148 -90)
		(property "Reference" "C4319"
			(at 0 0 270)
			(layer "F.SilkS")
			(hide yes)
			(effects
				(font
					(size 1.27 1.27)
				)
			)
		)
		(property "Value" ""
			(at 0 0 270)
			(layer "F.Fab")
			(effects
				(font
					(size 1.27 1.27)
				)
			)
		)
		(duplicate_pad_numbers_are_jumpers no)
		(fp_line
			(start -1.2954 0.5842)
			(end -1.2954 -0.5842)
			(stroke
				(width 0.1524)
				(type default)
			)
			(layer "F.SilkS")
		)
		(fp_line
			(start 1.2954 0.5842)
			(end -1.2954 0.5842)
			(stroke
				(width 0.1524)
				(type default)
			)
			(layer "F.SilkS")
		)
		(fp_line
			(start -1.2954 -0.5842)
			(end 1.2954 -0.5842)
			(stroke
				(width 0.1524)
				(type default)
			)
			(layer "F.SilkS")
		)
		(fp_line
			(start 1.2954 -0.5842)
			(end 1.2954 0.5842)
			(stroke
				(width 0.1524)
				(type default)
			)
			(layer "F.SilkS")
		)
		(fp_line
			(start -0.8636 0.4572)
			(end -0.8636 0.4064)
			(stroke
				(width 0.1)
				(type default)
			)
			(layer "F.Fab")
		)
		(fp_line
			(start 0.8636 0.4572)
			(end -0.8636 0.4572)
			(stroke
				(width 0.1)
				(type default)
			)
			(layer "F.Fab")
		)
		(fp_line
			(start -1.1938 0.4064)
			(end -1.1938 -0.4064)
			(stroke
				(width 0.1)
				(type default)
			)
			(layer "F.Fab")
		)
		(fp_line
			(start -0.8636 0.4064)
			(end -1.1938 0.4064)
			(stroke
				(width 0.1)
				(type default)
			)
			(layer "F.Fab")
		)
		(fp_line
			(start 0.8636 0.4064)
			(end 0.8636 0.4572)
			(stroke
				(width 0.1)
				(type default)
			)
			(layer "F.Fab")
		)
		(fp_line
			(start 1.1938 0.4064)
			(end 0.8636 0.4064)
			(stroke
				(width 0.1)
				(type default)
			)
			(layer "F.Fab")
		)
		(fp_line
			(start -1.1938 -0.4064)
			(end -0.8636 -0.4064)
			(stroke
				(width 0.1)
				(type default)
			)
			(layer "F.Fab")
		)
		(fp_line
			(start -0.8636 -0.4064)
			(end -0.8636 -0.4572)
			(stroke
				(width 0.1)
				(type default)
			)
			(layer "F.Fab")
		)
		(fp_line
			(start 0.8636 -0.4064)
			(end 1.1938 -0.4064)
			(stroke
				(width 0.1)
				(type default)
			)
			(layer "F.Fab")
		)
		(fp_line
			(start 1.1938 -0.4064)
			(end 1.1938 0.4064)
			(stroke
				(width 0.1)
				(type default)
			)
			(layer "F.Fab")
		)
		(fp_line
			(start -0.8636 -0.4572)
			(end 0.8636 -0.4572)
			(stroke
				(width 0.1)
				(type default)
			)
			(layer "F.Fab")
		)
		(fp_line
			(start 0.8636 -0.4572)
			(end 0.8636 -0.4064)
			(stroke
				(width 0.1)
				(type default)
			)
			(layer "F.Fab")
		)
		(pad "1" smd rect
			(at -0.7366 0 180)
			(size 0.7112 0.8128)
			(layers "F.Cu" "F.Mask" "F.Paste")
			(net "P0V8_PEX2")
		)
		(pad "2" smd rect
			(at 0.7366 0 180)
			(size 0.7112 0.8128)
			(layers "F.Cu" "F.Mask" "F.Paste")
			(net "GND")
		)
	)
	(footprint ""
		(layer "F.Cu")
		(at 322.718684 -356.244906 90)
		(property "Reference" "C540"
			(at 0 0 90)
			(layer "F.SilkS")
			(hide yes)
			(effects
				(font
					(size 1.27 1.27)
				)
			)
		)
		(property "Value" ""
			(at 0 0 90)
			(layer "F.Fab")
			(effects
				(font
					(size 1.27 1.27)
				)
			)
		)
		(duplicate_pad_numbers_are_jumpers no)
		(fp_line
			(start 0.299974 -0.150114)
			(end 0.299974 0.150114)
			(stroke
				(width 0.1)
				(type default)
			)
			(layer "F.Fab")
		)
		(fp_line
			(start -0.299974 -0.150114)
			(end 0.299974 -0.150114)
			(stroke
				(width 0.1)
				(type default)
			)
			(layer "F.Fab")
		)
		(fp_line
			(start 0.299974 0.150114)
			(end -0.299974 0.150114)
			(stroke
				(width 0.1)
				(type default)
			)
			(layer "F.Fab")
		)
		(fp_line
			(start -0.299974 0.150114)
			(end -0.299974 -0.150114)
			(stroke
				(width 0.1)
				(type default)
			)
			(layer "F.Fab")
		)
		(pad "1" smd rect
			(at -0.2667 0 90)
			(size 0.3048 0.381)
			(layers "F.Cu" "F.Mask" "F.Paste")
			(net "P5E_PEX2_STN5_TX_DN<85>")
		)
		(pad "2" smd rect
			(at 0.2667 0 90)
			(size 0.3048 0.381)
			(layers "F.Cu" "F.Mask" "F.Paste")
			(net "P5E_PEX2_STN5_TX_C_DN<85>")
		)
	)
	(footprint ""
		(layer "F.Cu")
		(at 364.234222 -135.77697 -90)
		(property "Reference" "PC819"
			(at 0 0 270)
			(layer "F.SilkS")
			(hide yes)
			(effects
				(font
					(size 1.27 1.27)
				)
			)
		)
		(property "Value" ""
			(at 0 0 270)
			(layer "F.Fab")
			(effects
				(font
					(size 1.27 1.27)
				)
			)
		)
		(duplicate_pad_numbers_are_jumpers no)
		(fp_line
			(start -1.524 0.762)
			(end -1.524 -0.762)
			(stroke
				(width 0.1524)
				(type default)
			)
			(layer "F.SilkS")
		)
		(fp_line
			(start 1.524 0.762)
			(end -1.524 0.762)
			(stroke
				(width 0.1524)
				(type default)
			)
			(layer "F.SilkS")
		)
		(fp_line
			(start -1.524 -0.762)
			(end 1.524 -0.762)
			(stroke
				(width 0.1524)
				(type default)
			)
			(layer "F.SilkS")
		)
		(fp_line
			(start 1.524 -0.762)
			(end 1.524 0.762)
			(stroke
				(width 0.1524)
				(type default)
			)
			(layer "F.SilkS")
		)
		(fp_line
			(start -1.1049 0.724916)
			(end 1.1049 0.724916)
			(stroke
				(width 0.1)
				(type default)
			)
			(layer "F.Fab")
		)
		(fp_line
			(start 1.1049 0.724916)
			(end 1.1049 -0.724916)
			(stroke
				(width 0.1)
				(type default)
			)
			(layer "F.Fab")
		)
		(fp_line
			(start -1.1049 -0.724916)
			(end -1.1049 0.724916)
			(stroke
				(width 0.1)
				(type default)
			)
			(layer "F.Fab")
		)
		(fp_line
			(start 1.1049 -0.724916)
			(end -1.1049 -0.724916)
			(stroke
				(width 0.1)
				(type default)
			)
			(layer "F.Fab")
		)
		(pad "1" smd rect
			(at -0.889 0 90)
			(size 1.016 1.27)
			(layers "F.Cu" "F.Mask" "F.Paste")
			(net "P12V_NIC6_R")
		)
		(pad "2" smd rect
			(at 0.889 0 90)
			(size 1.016 1.27)
			(layers "F.Cu" "F.Mask" "F.Paste")
			(net "GND")
		)
	)
	(footprint ""
		(layer "F.Cu")
		(at 155.380436 -110.088934)
		(property "Reference" "C262"
			(at 0 0 0)
			(layer "F.SilkS")
			(hide yes)
			(effects
				(font
					(size 1.27 1.27)
				)
			)
		)
		(property "Value" ""
			(at 0 0 0)
			(layer "F.Fab")
			(effects
				(font
					(size 1.27 1.27)
				)
			)
		)
		(duplicate_pad_numbers_are_jumpers no)
		(fp_line
			(start -0.299974 -0.150114)
			(end 0.299974 -0.150114)
			(stroke
				(width 0.1)
				(type default)
			)
			(layer "F.Fab")
		)
		(fp_line
			(start -0.299974 0.150114)
			(end -0.299974 -0.150114)
			(stroke
				(width 0.1)
				(type default)
			)
			(layer "F.Fab")
		)
		(fp_line
			(start 0.299974 -0.150114)
			(end 0.299974 0.150114)
			(stroke
				(width 0.1)
				(type default)
			)
			(layer "F.Fab")
		)
		(fp_line
			(start 0.299974 0.150114)
			(end -0.299974 0.150114)
			(stroke
				(width 0.1)
				(type default)
			)
			(layer "F.Fab")
		)
		(pad "1" smd rect
			(at -0.2667 0)
			(size 0.3048 0.381)
			(layers "F.Cu" "F.Mask" "F.Paste")
			(net "P5E_PEX1_STN1_TX_DP<22>")
		)
		(pad "2" smd rect
			(at 0.2667 0)
			(size 0.3048 0.381)
			(layers "F.Cu" "F.Mask" "F.Paste")
			(net "P5E_PEX1_STN1_TX_C_DP<22>")
		)
	)
	(footprint ""
		(layer "F.Cu")
		(at 235.965746 -120.381268 90)
		(property "Reference" "PR6896"
			(at 0 0 90)
			(layer "F.SilkS")
			(hide yes)
			(effects
				(font
					(size 1.27 1.27)
				)
			)
		)
		(property "Value" ""
			(at 0 0 90)
			(layer "F.Fab")
			(effects
				(font
					(size 1.27 1.27)
				)
			)
		)
		(duplicate_pad_numbers_are_jumpers no)
		(fp_line
			(start 0.7874 -0.4064)
			(end 0.7874 0.4064)
			(stroke
				(width 0.1524)
				(type default)
			)
			(layer "F.SilkS")
		)
		(fp_line
			(start -0.7874 -0.4064)
			(end 0.7874 -0.4064)
			(stroke
				(width 0.1524)
				(type default)
			)
			(layer "F.SilkS")
		)
		(fp_line
			(start 0.7874 0.4064)
			(end -0.7874 0.4064)
			(stroke
				(width 0.1524)
				(type default)
			)
			(layer "F.SilkS")
		)
		(fp_line
			(start -0.7874 0.4064)
			(end -0.7874 -0.4064)
			(stroke
				(width 0.1524)
				(type default)
			)
			(layer "F.SilkS")
		)
		(fp_line
			(start -0.12065 -0.305054)
			(end -0.12065 -0.2794)
			(stroke
				(width 0.1)
				(type default)
			)
			(layer "F.Fab")
		)
		(fp_line
			(start -0.67945 -0.305054)
			(end -0.12065 -0.305054)
			(stroke
				(width 0.1)
				(type default)
			)
			(layer "F.Fab")
		)
		(fp_line
			(start 0.67945 -0.3048)
			(end 0.67945 0.3048)
			(stroke
				(width 0.1)
				(type default)
			)
			(layer "F.Fab")
		)
		(fp_line
			(start 0.12065 -0.3048)
			(end 0.67945 -0.3048)
			(stroke
				(width 0.1)
				(type default)
			)
			(layer "F.Fab")
		)
		(fp_line
			(start 0.12065 -0.2794)
			(end 0.12065 -0.3048)
			(stroke
				(width 0.1)
				(type default)
			)
			(layer "F.Fab")
		)
		(fp_line
			(start -0.12065 -0.2794)
			(end 0.12065 -0.2794)
			(stroke
				(width 0.1)
				(type default)
			)
			(layer "F.Fab")
		)
		(fp_line
			(start 0.120396 0.2794)
			(end -0.12065 0.2794)
			(stroke
				(width 0.1)
				(type default)
			)
			(layer "F.Fab")
		)
		(fp_line
			(start -0.12065 0.2794)
			(end -0.12065 0.3048)
			(stroke
				(width 0.1)
				(type default)
			)
			(layer "F.Fab")
		)
		(fp_line
			(start 0.67945 0.3048)
			(end 0.120396 0.3048)
			(stroke
				(width 0.1)
				(type default)
			)
			(layer "F.Fab")
		)
		(fp_line
			(start 0.120396 0.3048)
			(end 0.120396 0.2794)
			(stroke
				(width 0.1)
				(type default)
			)
			(layer "F.Fab")
		)
		(fp_line
			(start -0.12065 0.3048)
			(end -0.67945 0.3048)
			(stroke
				(width 0.1)
				(type default)
			)
			(layer "F.Fab")
		)
		(fp_line
			(start -0.67945 0.3048)
			(end -0.67945 -0.305054)
			(stroke
				(width 0.1)
				(type default)
			)
			(layer "F.Fab")
		)
		(pad "1" smd circle
			(at -0.40005 0 90)
			(size 0 0)
			(layers "F.Cu" "F.Mask" "F.Paste")
			(net "P12V_NIC3_CO_FLTB")
		)
		(pad "2" smd circle
			(at 0.40005 0 90)
			(size 0 0)
			(layers "F.Cu" "F.Mask" "F.Paste")
			(net "P3V3_AUX")
		)
	)
	(footprint ""
		(layer "F.Cu")
		(at 462.804764 -521.743686 180)
		(property "Reference" "SCREW_3"
			(at -3.2385 -1.402334 0)
			(unlocked yes)
			(layer "B.SilkS")
			(effects
				(font
					(size 0.7874 0.5842)
					(thickness 0.1524)
				)
				(justify mirror)
			)
		)
		(property "Value" ""
			(at 0 0 180)
			(layer "F.Fab")
			(effects
				(font
					(size 1.27 1.27)
				)
			)
		)
		(duplicate_pad_numbers_are_jumpers no)
		(pad "1" thru_hole circle
			(at 0 0 180)
			(size 0.4572 0.4572)
			(drill 0.2032)
			(layers "*.Cu" "*.Mask")
			(remove_unused_layers no)
			(net "Net_9161")
			(clearance 0.127)
			(thermal_gap 0.127)
			(padstack
				(mode front_inner_back)
				(layer "Inner"
					(shape circle)
					(size 0.4572 0.4572)
					(clearance 0.127)
				)
				(layer "B.Cu"
					(shape circle)
					(size 0.508 0.508)
					(clearance 0.1016)
				)
			)
		)
	)
	(footprint ""
		(layer "F.Cu")
		(at 187.032392 -350.098614 90)
		(property "Reference" "C2536"
			(at 0 0 90)
			(layer "F.SilkS")
			(hide yes)
			(effects
				(font
					(size 1.27 1.27)
				)
			)
		)
		(property "Value" ""
			(at 0 0 90)
			(layer "F.Fab")
			(effects
				(font
					(size 1.27 1.27)
				)
			)
		)
		(duplicate_pad_numbers_are_jumpers no)
		(fp_line
			(start 0.299974 -0.150114)
			(end 0.299974 0.150114)
			(stroke
				(width 0.1)
				(type default)
			)
			(layer "F.Fab")
		)
		(fp_line
			(start -0.299974 -0.150114)
			(end 0.299974 -0.150114)
			(stroke
				(width 0.1)
				(type default)
			)
			(layer "F.Fab")
		)
		(fp_line
			(start 0.299974 0.150114)
			(end -0.299974 0.150114)
			(stroke
				(width 0.1)
				(type default)
			)
			(layer "F.Fab")
		)
		(fp_line
			(start -0.299974 0.150114)
			(end -0.299974 -0.150114)
			(stroke
				(width 0.1)
				(type default)
			)
			(layer "F.Fab")
		)
		(pad "1" smd rect
			(at -0.2667 0 90)
			(size 0.3048 0.381)
			(layers "F.Cu" "F.Mask" "F.Paste")
			(net "P5E_PEX1_STN4_TX_DP<67>")
		)
		(pad "2" smd rect
			(at 0.2667 0 90)
			(size 0.3048 0.381)
			(layers "F.Cu" "F.Mask" "F.Paste")
			(net "P5E_PEX1_STN4_TX_C_DP<67>")
		)
	)
	(footprint ""
		(layer "F.Cu")
		(at 340.561422 -188.38545 180)
		(property "Reference" "R4239"
			(at 0 0 180)
			(layer "F.SilkS")
			(hide yes)
			(effects
				(font
					(size 1.27 1.27)
				)
			)
		)
		(property "Value" ""
			(at 0 0 180)
			(layer "F.Fab")
			(effects
				(font
					(size 1.27 1.27)
				)
			)
		)
		(duplicate_pad_numbers_are_jumpers no)
		(fp_line
			(start 0.7874 0.4064)
			(end -0.7874 0.4064)
			(stroke
				(width 0.1524)
				(type default)
			)
			(layer "F.SilkS")
		)
		(fp_line
			(start 0.7874 -0.4064)
			(end 0.7874 0.4064)
			(stroke
				(width 0.1524)
				(type default)
			)
			(layer "F.SilkS")
		)
		(fp_line
			(start -0.7874 0.4064)
			(end -0.7874 -0.4064)
			(stroke
				(width 0.1524)
				(type default)
			)
			(layer "F.SilkS")
		)
		(fp_line
			(start -0.7874 -0.4064)
			(end 0.7874 -0.4064)
			(stroke
				(width 0.1524)
				(type default)
			)
			(layer "F.SilkS")
		)
		(fp_line
			(start 0.67945 0.3048)
			(end 0.120396 0.3048)
			(stroke
				(width 0.1)
				(type default)
			)
			(layer "F.Fab")
		)
		(fp_line
			(start 0.67945 -0.3048)
			(end 0.67945 0.3048)
			(stroke
				(width 0.1)
				(type default)
			)
			(layer "F.Fab")
		)
		(fp_line
			(start 0.12065 -0.2794)
			(end 0.12065 -0.3048)
			(stroke
				(width 0.1)
				(type default)
			)
			(layer "F.Fab")
		)
		(fp_line
			(start 0.12065 -0.3048)
			(end 0.67945 -0.3048)
			(stroke
				(width 0.1)
				(type default)
			)
			(layer "F.Fab")
		)
		(fp_line
			(start 0.120396 0.3048)
			(end 0.120396 0.2794)
			(stroke
				(width 0.1)
				(type default)
			)
			(layer "F.Fab")
		)
		(fp_line
			(start 0.120396 0.2794)
			(end -0.12065 0.2794)
			(stroke
				(width 0.1)
				(type default)
			)
			(layer "F.Fab")
		)
		(fp_line
			(start -0.12065 0.3048)
			(end -0.67945 0.3048)
			(stroke
				(width 0.1)
				(type default)
			)
			(layer "F.Fab")
		)
		(fp_line
			(start -0.12065 0.2794)
			(end -0.12065 0.3048)
			(stroke
				(width 0.1)
				(type default)
			)
			(layer "F.Fab")
		)
		(fp_line
			(start -0.12065 -0.2794)
			(end 0.12065 -0.2794)
			(stroke
				(width 0.1)
				(type default)
			)
			(layer "F.Fab")
		)
		(fp_line
			(start -0.12065 -0.305054)
			(end -0.12065 -0.2794)
			(stroke
				(width 0.1)
				(type default)
			)
			(layer "F.Fab")
		)
		(fp_line
			(start -0.67945 0.3048)
			(end -0.67945 -0.305054)
			(stroke
				(width 0.1)
				(type default)
			)
			(layer "F.Fab")
		)
		(fp_line
			(start -0.67945 -0.305054)
			(end -0.12065 -0.305054)
			(stroke
				(width 0.1)
				(type default)
			)
			(layer "F.Fab")
		)
		(pad "1" smd circle
			(at -0.40005 0 180)
			(size 0 0)
			(layers "F.Cu" "F.Mask" "F.Paste")
			(net "P3V3_AUX")
		)
		(pad "2" smd circle
			(at 0.40005 0 180)
			(size 0 0)
			(layers "F.Cu" "F.Mask" "F.Paste")
			(net "USB_DEBUG_PWR_BTN_N")
		)
	)
)
